(kicad_pcb
	(version 20241229)
	(generator "pcbnew")
	(generator_version "9.0")
	(general
		(thickness 1.62)
		(legacy_teardrops no)
	)
	(paper "A3")
	(title_block
		(title "COM Express 7 Baseboard")
		(date "2025-02-04")
		(rev "1.1.2")
		(company "Antmicro Ltd")
		(comment 1 "www.antmicro.com")
		(comment 9 "footprints 263-268 of 802")
	)
	(layers
		(0 "F.Cu" signal)
		(4 "In1.Cu" signal)
		(6 "In2.Cu" signal)
		(8 "In3.Cu" signal)
		(10 "In4.Cu" signal)
		(12 "In5.Cu" signal)
		(14 "In6.Cu" signal)
		(2 "B.Cu" signal)
		(9 "F.Adhes" user "F.Adhesive")
		(11 "B.Adhes" user "B.Adhesive")
		(13 "F.Paste" user)
		(15 "B.Paste" user)
		(5 "F.SilkS" user "F.Silkscreen")
		(7 "B.SilkS" user "B.Silkscreen")
		(1 "F.Mask" user)
		(3 "B.Mask" user)
		(17 "Dwgs.User" user "User.Drawings")
		(19 "Cmts.User" user "User.Comments")
		(21 "Eco1.User" user "User.Eco1")
		(23 "Eco2.User" user "User.Eco2")
		(25 "Edge.Cuts" user)
		(27 "Margin" user)
		(31 "F.CrtYd" user "F.Courtyard")
		(29 "B.CrtYd" user "B.Courtyard")
		(35 "F.Fab" user)
		(33 "B.Fab" user)
	)
	(footprint "antmicro-footprints:R_0402_1005Metric"
		(layer "F.Cu")
		(at 193.757107 130.907107 -135)
		(descr "Resistor SMD 0402")
		(tags "resistor SMD 0402")
		(property "Reference" "R226"
			(at -3.65 -0.4 45)
			(layer "F.SilkS")
			(effects
				(font
					(size 0.7 0.7)
					(thickness 0.15)
				)
				(justify right bottom)
			)
		)
		(property "Value" "R_1k_0402"
			(at -1.011843 1.772046 45)
			(layer "F.Fab")
			(effects
				(font
					(size 0.7 0.7)
					(thickness 0.15)
				)
				(justify right bottom)
			)
		)
		(property "Datasheet" "https://www.bourns.com/docs/product-datasheets/cr.pdf"
			(at 0 0 45)
			(layer "F.Fab")
			(hide yes)
			(effects
				(font
					(size 1.27 1.27)
					(thickness 0.15)
				)
			)
		)
		(property "Author" "Antmicro"
			(at 389.1 265.22 45)
			(layer "F.Fab")
			(hide yes)
			(effects
				(font
					(size 1 1)
					(thickness 0.15)
				)
			)
		)
		(property "License" "Apache-2.0"
			(at 389.1 265.22 45)
			(layer "F.Fab")
			(hide yes)
			(effects
				(font
					(size 1 1)
					(thickness 0.15)
				)
			)
		)
		(property "MPN" "CR0402-FX-1001GLF"
			(at 389.1 265.22 45)
			(layer "F.Fab")
			(hide yes)
			(effects
				(font
					(size 1 1)
					(thickness 0.15)
				)
			)
		)
		(property "Manufacturer" "Bourns"
			(at 389.1 265.22 45)
			(layer "F.Fab")
			(hide yes)
			(effects
				(font
					(size 1 1)
					(thickness 0.15)
				)
			)
		)
		(property "Public" "False"
			(at 389.1 265.22 45)
			(layer "F.Fab")
			(hide yes)
			(effects
				(font
					(size 1 1)
					(thickness 0.15)
				)
			)
		)
		(property "Tolerance" "1%"
			(at 389.1 265.22 45)
			(layer "F.Fab")
			(hide yes)
			(effects
				(font
					(size 1 1)
					(thickness 0.15)
				)
			)
		)
		(property "Val" "1k"
			(at 389.1 265.22 45)
			(layer "F.Fab")
			(hide yes)
			(effects
				(font
					(size 1 1)
					(thickness 0.15)
				)
			)
		)
		(sheetname "PCIe redriver")
		(sheetfile "pcie_redriver.kicad_sch")
		(attr smd dnp)
		(fp_poly
			(pts
				(xy -0.925 -0.47) (xy 0.925 -0.47) (xy 0.925 0.47) (xy -0.925 0.47)
			)
			(stroke
				(width 0.05)
				(type default)
			)
			(fill no)
			(layer "F.CrtYd")
		)
		(fp_poly
			(pts
				(xy -0.5 -0.25) (xy 0.5 -0.25) (xy 0.5 0.25) (xy -0.5 0.25)
			)
			(stroke
				(width 0.15)
				(type solid)
			)
			(fill no)
			(layer "F.Fab")
		)
		(pad "1" smd roundrect
			(at -0.48 0 225)
			(size 0.59 0.64)
			(layers "F.Cu" "F.Mask" "F.Paste")
			(roundrect_rratio 0.25)
			(net 1 "GND")
			(pintype "passive")
			(teardrops
				(best_length_ratio 0.2)
				(max_length 1)
				(best_width_ratio 0.9)
				(max_width 2)
				(curved_edges yes)
				(filter_ratio 0.9)
				(enabled yes)
				(allow_two_segments yes)
				(prefer_zone_connections yes)
			)
		)
		(pad "2" smd roundrect
			(at 0.48 0 225)
			(size 0.59 0.64)
			(layers "F.Cu" "F.Mask" "F.Paste")
			(roundrect_rratio 0.25)
			(net 976 "/PCIe redriver/RX_EQ2")
			(pintype "passive")
			(teardrops
				(best_length_ratio 0.2)
				(max_length 1)
				(best_width_ratio 0.9)
				(max_width 2)
				(curved_edges yes)
				(filter_ratio 0.9)
				(enabled yes)
				(allow_two_segments yes)
				(prefer_zone_connections yes)
			)
		)
	)
	(footprint "antmicro-footprints:R_0402_1005Metric"
		(layer "F.Cu")
		(at 212.59 133.26 180)
		(descr "Resistor SMD 0402")
		(tags "resistor SMD 0402")
		(property "Reference" "R183"
			(at 0.79 -0.42 0)
			(layer "F.SilkS")
			(effects
				(font
					(size 0.7 0.7)
					(thickness 0.15)
				)
				(justify right bottom)
			)
		)
		(property "Value" "R_1k_0402"
			(at -1.011843 1.772047 0)
			(layer "F.Fab")
			(effects
				(font
					(size 0.7 0.7)
					(thickness 0.15)
				)
				(justify right bottom)
			)
		)
		(property "Datasheet" "https://www.bourns.com/docs/product-datasheets/cr.pdf"
			(at 0 0 180)
			(layer "F.Fab")
			(hide yes)
			(effects
				(font
					(size 1.27 1.27)
					(thickness 0.15)
				)
			)
		)
		(property "Author" "Antmicro"
			(at 425.18 266.52 0)
			(layer "F.Fab")
			(hide yes)
			(effects
				(font
					(size 1 1)
					(thickness 0.15)
				)
			)
		)
		(property "License" "Apache-2.0"
			(at 425.18 266.52 0)
			(layer "F.Fab")
			(hide yes)
			(effects
				(font
					(size 1 1)
					(thickness 0.15)
				)
			)
		)
		(property "MPN" "CR0402-FX-1001GLF"
			(at 425.18 266.52 0)
			(layer "F.Fab")
			(hide yes)
			(effects
				(font
					(size 1 1)
					(thickness 0.15)
				)
			)
		)
		(property "Manufacturer" "Bourns"
			(at 425.18 266.52 0)
			(layer "F.Fab")
			(hide yes)
			(effects
				(font
					(size 1 1)
					(thickness 0.15)
				)
			)
		)
		(property "Public" "False"
			(at 425.18 266.52 0)
			(layer "F.Fab")
			(hide yes)
			(effects
				(font
					(size 1 1)
					(thickness 0.15)
				)
			)
		)
		(property "Tolerance" "1%"
			(at 425.18 266.52 0)
			(layer "F.Fab")
			(hide yes)
			(effects
				(font
					(size 1 1)
					(thickness 0.15)
				)
			)
		)
		(property "Val" "1k"
			(at 425.18 266.52 0)
			(layer "F.Fab")
			(hide yes)
			(effects
				(font
					(size 1 1)
					(thickness 0.15)
				)
			)
		)
		(sheetname "PCIe misc")
		(sheetfile "pcie_misc.kicad_sch")
		(attr smd)
		(fp_rect
			(start -0.925 -0.47)
			(end 0.925 0.47)
			(stroke
				(width 0.05)
				(type default)
			)
			(fill no)
			(layer "F.CrtYd")
		)
		(fp_rect
			(start -0.5 -0.25)
			(end 0.5 0.25)
			(stroke
				(width 0.15)
				(type solid)
			)
			(fill no)
			(layer "F.Fab")
		)
		(pad "1" smd roundrect
			(at -0.48 0 180)
			(size 0.59 0.64)
			(layers "F.Cu" "F.Mask" "F.Paste")
			(roundrect_rratio 0.25)
			(net 603 "Net-(U37-~{OE1})")
			(pintype "passive")
			(teardrops
				(best_length_ratio 0.2)
				(max_length 1)
				(best_width_ratio 0.9)
				(max_width 2)
				(curved_edges yes)
				(filter_ratio 0.9)
				(enabled yes)
				(allow_two_segments yes)
				(prefer_zone_connections yes)
			)
		)
		(pad "2" smd roundrect
			(at 0.48 0 180)
			(size 0.59 0.64)
			(layers "F.Cu" "F.Mask" "F.Paste")
			(roundrect_rratio 0.25)
			(net 1 "GND")
			(pintype "passive")
			(teardrops
				(best_length_ratio 0.2)
				(max_length 1)
				(best_width_ratio 0.9)
				(max_width 2)
				(curved_edges yes)
				(filter_ratio 0.9)
				(enabled yes)
				(allow_two_segments yes)
				(prefer_zone_connections yes)
			)
		)
	)
	(footprint "antmicro-footprints:C_0603_1608Metric"
		(layer "F.Cu")
		(at 177.52 110.61)
		(descr "Capacitor SMD 0603")
		(tags "capacitor 0603")
		(property "Reference" "C74"
			(at -3.37 0.55 0)
			(layer "F.SilkS")
			(effects
				(font
					(size 0.7 0.7)
					(thickness 0.15)
				)
				(justify left bottom)
			)
		)
		(property "Value" "C_22u_16V_0603"
			(at -1.42757 1.770288 0)
			(layer "F.Fab")
			(effects
				(font
					(size 0.7 0.7)
					(thickness 0.15)
				)
				(justify left bottom)
			)
		)
		(property "Datasheet" "https://product.samsungsem.com/mlcc/CL10A226MO7JZN.do"
			(at 0 0 0)
			(layer "F.Fab")
			(hide yes)
			(effects
				(font
					(size 1.27 1.27)
					(thickness 0.15)
				)
			)
		)
		(property "Author" "Antmicro"
			(at 0 0 0)
			(layer "F.Fab")
			(hide yes)
			(effects
				(font
					(size 1 1)
					(thickness 0.15)
				)
			)
		)
		(property "Dielectric" ""
			(at 0 0 0)
			(layer "F.Fab")
			(hide yes)
			(effects
				(font
					(size 1 1)
					(thickness 0.15)
				)
			)
		)
		(property "License" "Apache-2.0"
			(at 0 0 0)
			(layer "F.Fab")
			(hide yes)
			(effects
				(font
					(size 1 1)
					(thickness 0.15)
				)
			)
		)
		(property "MPN" "CL10A226MO7JZNC"
			(at 0 0 0)
			(layer "F.Fab")
			(hide yes)
			(effects
				(font
					(size 1 1)
					(thickness 0.15)
				)
			)
		)
		(property "Manufacturer" "Samsung Electro-Mechanics"
			(at 0 0 0)
			(layer "F.Fab")
			(hide yes)
			(effects
				(font
					(size 1 1)
					(thickness 0.15)
				)
			)
		)
		(property "Public" "False"
			(at 0 0 0)
			(layer "F.Fab")
			(hide yes)
			(effects
				(font
					(size 1 1)
					(thickness 0.15)
				)
			)
		)
		(property "Val" "22u"
			(at 0 0 0)
			(layer "F.Fab")
			(hide yes)
			(effects
				(font
					(size 1 1)
					(thickness 0.15)
				)
			)
		)
		(property "Voltage" "16V"
			(at 0 0 0)
			(layer "F.Fab")
			(hide yes)
			(effects
				(font
					(size 1 1)
					(thickness 0.15)
				)
			)
		)
		(sheetname "M.2 key M #1")
		(sheetfile "m2keym_low.kicad_sch")
		(attr smd)
		(fp_line
			(start -0.15 -0.4)
			(end 0.15 -0.4)
			(stroke
				(width 0.15)
				(type solid)
			)
			(layer "F.SilkS")
		)
		(fp_line
			(start -0.15 0.4)
			(end 0.15 0.4)
			(stroke
				(width 0.15)
				(type solid)
			)
			(layer "F.SilkS")
		)
		(fp_rect
			(start -1.25 -0.65)
			(end 1.25 0.65)
			(stroke
				(width 0.05)
				(type solid)
			)
			(fill no)
			(layer "F.CrtYd")
		)
		(fp_rect
			(start -0.8 -0.4)
			(end 0.8 0.4)
			(stroke
				(width 0.15)
				(type solid)
			)
			(fill no)
			(layer "F.Fab")
		)
		(pad "1" smd roundrect
			(at -0.7 0)
			(size 0.8 1)
			(layers "F.Cu" "F.Mask" "F.Paste")
			(roundrect_rratio 0.2)
			(net 1 "GND")
			(pintype "passive")
			(teardrops
				(best_length_ratio 0.2)
				(max_length 1)
				(best_width_ratio 0.9)
				(max_width 2)
				(curved_edges yes)
				(filter_ratio 0.9)
				(enabled yes)
				(allow_two_segments yes)
				(prefer_zone_connections yes)
			)
		)
		(pad "2" smd roundrect
			(at 0.7 0)
			(size 0.8 1)
			(layers "F.Cu" "F.Mask" "F.Paste")
			(roundrect_rratio 0.2)
			(net 969 "/M.2 key M #1/M2_3V3")
			(pintype "passive")
			(teardrops
				(best_length_ratio 0.2)
				(max_length 1)
				(best_width_ratio 0.9)
				(max_width 2)
				(curved_edges yes)
				(filter_ratio 0.9)
				(enabled yes)
				(allow_two_segments yes)
				(prefer_zone_connections yes)
			)
		)
	)
	(footprint "antmicro-footprints:R_0402_1005Metric"
		(layer "F.Cu")
		(at 239.000001 78.5 90)
		(descr "Resistor SMD 0402")
		(tags "resistor SMD 0402")
		(property "Reference" "R163"
			(at -1.1 -0.400001 90)
			(layer "F.SilkS")
			(effects
				(font
					(size 0.7 0.7)
					(thickness 0.15)
				)
				(justify right top)
			)
		)
		(property "Value" "R_5k1_0402"
			(at -4.236842 54.437047 90)
			(layer "F.Fab")
			(hide yes)
			(effects
				(font
					(size 0.7 0.7)
					(thickness 0.15)
				)
				(justify left bottom)
			)
		)
		(property "Datasheet" "https://www.bourns.com/docs/product-datasheets/cr.pdf"
			(at 0 0 90)
			(layer "F.Fab")
			(hide yes)
			(effects
				(font
					(size 1.27 1.27)
					(thickness 0.15)
				)
			)
		)
		(property "Author" "Antmicro"
			(at 0 0 90)
			(layer "F.Fab")
			(hide yes)
			(effects
				(font
					(size 1 1)
					(thickness 0.15)
				)
			)
		)
		(property "License" "Apache-2.0"
			(at 0 0 90)
			(layer "F.Fab")
			(hide yes)
			(effects
				(font
					(size 1 1)
					(thickness 0.15)
				)
			)
		)
		(property "MPN" "CR0402-FX-5101GLF"
			(at 0 0 90)
			(layer "F.Fab")
			(hide yes)
			(effects
				(font
					(size 1 1)
					(thickness 0.15)
				)
			)
		)
		(property "Manufacturer" "Bourns"
			(at 0 0 90)
			(layer "F.Fab")
			(hide yes)
			(effects
				(font
					(size 1 1)
					(thickness 0.15)
				)
			)
		)
		(property "Public" "False"
			(at 0 0 90)
			(layer "F.Fab")
			(hide yes)
			(effects
				(font
					(size 1 1)
					(thickness 0.15)
				)
			)
		)
		(property "Tolerance" "1%"
			(at 0 0 90)
			(layer "F.Fab")
			(hide yes)
			(effects
				(font
					(size 1 1)
					(thickness 0.15)
				)
			)
		)
		(property "Val" "5k1"
			(at 0 0 90)
			(layer "F.Fab")
			(hide yes)
			(effects
				(font
					(size 1 1)
					(thickness 0.15)
				)
			)
		)
		(sheetname "Com Express 7 MGMT")
		(sheetfile "com_express_7_mgmt.kicad_sch")
		(attr smd)
		(fp_rect
			(start -0.925 -0.47)
			(end 0.925 0.47)
			(stroke
				(width 0.05)
				(type default)
			)
			(fill no)
			(layer "F.CrtYd")
		)
		(fp_rect
			(start -0.5 -0.25)
			(end 0.5 0.25)
			(stroke
				(width 0.15)
				(type solid)
			)
			(fill no)
			(layer "F.Fab")
		)
		(pad "1" smd roundrect
			(at -0.48 0 90)
			(size 0.59 0.64)
			(layers "F.Cu" "F.Mask" "F.Paste")
			(roundrect_rratio 0.25)
			(net 401 "/Com Express 7 MGMT/FAM_TACH")
			(pintype "passive")
			(teardrops
				(best_length_ratio 0.2)
				(max_length 1)
				(best_width_ratio 0.9)
				(max_width 2)
				(curved_edges yes)
				(filter_ratio 0.9)
				(enabled yes)
				(allow_two_segments yes)
				(prefer_zone_connections yes)
			)
		)
		(pad "2" smd roundrect
			(at 0.48 0 90)
			(size 0.59 0.64)
			(layers "F.Cu" "F.Mask" "F.Paste")
			(roundrect_rratio 0.25)
			(net 2 "+3V3")
			(pintype "passive")
			(teardrops
				(best_length_ratio 0.2)
				(max_length 1)
				(best_width_ratio 0.9)
				(max_width 2)
				(curved_edges yes)
				(filter_ratio 0.9)
				(enabled yes)
				(allow_two_segments yes)
				(prefer_zone_connections yes)
			)
		)
	)
	(footprint "antmicro-footprints:R_0402_1005Metric"
		(layer "F.Cu")
		(at 189.347802 138.065006 -135)
		(descr "Resistor SMD 0402")
		(tags "resistor SMD 0402")
		(property "Reference" "R230"
			(at 1.069205 -0.465818 45)
			(layer "F.SilkS")
			(effects
				(font
					(size 0.7 0.7)
					(thickness 0.15)
				)
				(justify right bottom)
			)
		)
		(property "Value" "R_1k_0402"
			(at -1.011843 1.772046 45)
			(layer "F.Fab")
			(effects
				(font
					(size 0.7 0.7)
					(thickness 0.15)
				)
				(justify right bottom)
			)
		)
		(property "Datasheet" "https://www.bourns.com/docs/product-datasheets/cr.pdf"
			(at 0 0 45)
			(layer "B.Fab")
			(hide yes)
			(effects
				(font
					(size 1.27 1.27)
					(thickness 0.15)
				)
				(justify mirror)
			)
		)
		(property "Author" "Antmicro"
			(at 0 0 45)
			(layer "F.Fab")
			(hide yes)
			(effects
				(font
					(size 1 1)
					(thickness 0.15)
				)
			)
		)
		(property "License" "Apache-2.0"
			(at 0 0 45)
			(layer "F.Fab")
			(hide yes)
			(effects
				(font
					(size 1 1)
					(thickness 0.15)
				)
			)
		)
		(property "MPN" "CR0402-FX-1001GLF"
			(at 0 0 45)
			(layer "F.Fab")
			(hide yes)
			(effects
				(font
					(size 1 1)
					(thickness 0.15)
				)
			)
		)
		(property "Manufacturer" "Bourns"
			(at 0 0 45)
			(layer "F.Fab")
			(hide yes)
			(effects
				(font
					(size 1 1)
					(thickness 0.15)
				)
			)
		)
		(property "Public" "False"
			(at 0 0 45)
			(layer "F.Fab")
			(hide yes)
			(effects
				(font
					(size 1 1)
					(thickness 0.15)
				)
			)
		)
		(property "Tolerance" "1%"
			(at 0 0 45)
			(layer "F.Fab")
			(hide yes)
			(effects
				(font
					(size 1 1)
					(thickness 0.15)
				)
			)
		)
		(property "Val" "1k"
			(at 0 0 45)
			(layer "F.Fab")
			(hide yes)
			(effects
				(font
					(size 1 1)
					(thickness 0.15)
				)
			)
		)
		(sheetname "PCIe redriver")
		(sheetfile "pcie_redriver.kicad_sch")
		(attr smd dnp)
		(fp_poly
			(pts
				(xy -0.925 -0.47) (xy 0.925 -0.47) (xy 0.925 0.47) (xy -0.925 0.47)
			)
			(stroke
				(width 0.05)
				(type default)
			)
			(fill no)
			(layer "F.CrtYd")
		)
		(fp_poly
			(pts
				(xy -0.5 -0.25) (xy 0.5 -0.25) (xy 0.5 0.25) (xy -0.5 0.25)
			)
			(stroke
				(width 0.15)
				(type solid)
			)
			(fill no)
			(layer "F.Fab")
		)
		(pad "1" smd roundrect
			(at -0.48 0 225)
			(size 0.59 0.64)
			(layers "F.Cu" "F.Mask" "F.Paste")
			(roundrect_rratio 0.25)
			(net 1 "GND")
			(pintype "passive")
			(teardrops
				(best_length_ratio 0.2)
				(max_length 1)
				(best_width_ratio 0.9)
				(max_width 2)
				(curved_edges yes)
				(filter_ratio 0.9)
				(enabled yes)
				(allow_two_segments yes)
				(prefer_zone_connections yes)
			)
		)
		(pad "2" smd roundrect
			(at 0.48 0 225)
			(size 0.59 0.64)
			(layers "F.Cu" "F.Mask" "F.Paste")
			(roundrect_rratio 0.25)
			(net 978 "/PCIe redriver/RX_EQ0")
			(pintype "passive")
			(teardrops
				(best_length_ratio 0.2)
				(max_length 1)
				(best_width_ratio 0.9)
				(max_width 2)
				(curved_edges yes)
				(filter_ratio 0.9)
				(enabled yes)
				(allow_two_segments yes)
				(prefer_zone_connections yes)
			)
		)
	)
	(footprint "antmicro-footprints:TP_SMD_0.75mm"
		(layer "F.Cu")
		(at 154.4 128.71)
		(property "Reference" "TP66"
			(at 0.4 -3.3 90)
			(layer "F.SilkS")
			(effects
				(font
					(size 0.7 0.7)
					(thickness 0.15)
				)
				(justify left bottom)
			)
		)
		(property "Value" "TP_0.75mm_SMD"
			(at 0 1.2 0)
			(layer "F.Fab")
			(effects
				(font
					(size 0.7 0.7)
					(thickness 0.15)
				)
				(justify left bottom)
			)
		)
		(property "Author" "Antmicro"
			(at 0 0 0)
			(layer "F.Fab")
			(hide yes)
			(effects
				(font
					(size 1 1)
					(thickness 0.15)
				)
			)
		)
		(property "License" "Apache-2.0"
			(at 0 0 0)
			(layer "F.Fab")
			(hide yes)
			(effects
				(font
					(size 1 1)
					(thickness 0.15)
				)
			)
		)
		(property "MPN" ""
			(at 0 0 0)
			(layer "F.Fab")
			(hide yes)
			(effects
				(font
					(size 1 1)
					(thickness 0.15)
				)
			)
		)
		(property "Manufacturer" ""
			(at 0 0 0)
			(layer "F.Fab")
			(hide yes)
			(effects
				(font
					(size 1 1)
					(thickness 0.15)
				)
			)
		)
		(property "Public" "False"
			(at 0 0 0)
			(layer "F.Fab")
			(hide yes)
			(effects
				(font
					(size 1 1)
					(thickness 0.15)
				)
			)
		)
		(sheetname "KR to SFI #1")
		(sheetfile "kr_sfi.kicad_sch")
		(attr exclude_from_pos_files exclude_from_bom)
		(fp_circle
			(center 0 0)
			(end 0.475 0)
			(stroke
				(width 0.05)
				(type default)
			)
			(fill no)
			(layer "F.CrtYd")
		)
		(pad "1" smd circle
			(at 0 0)
			(size 0.75 0.75)
			(layers "F.Cu" "F.Mask")
			(net 729 "Net-(U43C-AMUXB)")
			(pinfunction "1")
			(pintype "passive")
			(teardrops
				(best_length_ratio 0.4)
				(max_length 1)
				(best_width_ratio 0.9)
				(max_width 2)
				(curved_edges yes)
				(filter_ratio 0.9)
				(enabled yes)
				(allow_two_segments yes)
				(prefer_zone_connections yes)
			)
		)
	)
)
